# BASEBOARD_FAB2 (Tioga Pass) — schematic netlist excerpt (pin names and nets, part order shuffled) for the footprints in the layout excerpt that follows; sources: Cadence DE-HDL packaged netlist, KiCad conversion of Wiwynn_Tioga_Pass_MB.brd

CT61  CAP  1000PF 50V 10% X7R  pkg 0402LF  page 214 : A = A_TSENSE_PVCCIO_CPU1 ; B = GND
C1C13  CAP_A  1.0UF 6.3V 10% X6S  pkg 0402V  page 206 : A = VR_PVCCIN_CPU1_VD12 ; B = GND
C2A11  CAP_A  47UF 4V 20% X5R  pkg 0603V  page 228 : A = PVDDQ_KLM ; B = GND

(kicad_pcb
	(version 20260206)
	(generator "pcbnew")
	(generator_version "10.0")
	(general
		(thickness 1.6)
		(legacy_teardrops no)
	)
	(paper "A4")
	(title_block
		(title "Wiwynn_Tioga_Pass_MB.brd")
		(comment 1 "Tioga Pass / footprints 2091-2093 of 4770")
	)
	(layers
		(0 "F.Cu" signal "TOP")
		(4 "In1.Cu" signal "L2GND")
		(6 "In2.Cu" signal "L3")
		(8 "In3.Cu" signal "L4GND")
		(10 "In4.Cu" signal "L5")
		(12 "In5.Cu" signal "L6GND")
		(14 "In6.Cu" signal "L7VCC")
		(16 "In7.Cu" signal "L8VCC")
		(18 "In8.Cu" signal "L9GND")
		(20 "In9.Cu" signal "L10")
		(22 "In10.Cu" signal "L11GND")
		(24 "In11.Cu" signal "L12")
		(26 "In12.Cu" signal "L13GND")
		(2 "B.Cu" signal "BOTTOM")
		(9 "F.Adhes" user "F.Adhesive")
		(11 "B.Adhes" user "B.Adhesive")
		(13 "F.Paste" user "Package Geometry/Pastemask Top")
		(15 "B.Paste" user "Package Geometry/Pastemask Bottom")
		(5 "F.SilkS" user "Ref Des/Silkscreen Top")
		(7 "B.SilkS" user "Ref Des/Silkscreen Bottom")
		(1 "F.Mask" user "Board Geometry/Soldermask Top")
		(3 "B.Mask" user "Board Geometry/Soldermask Bottom")
		(17 "Dwgs.User" user "User.Drawings")
		(19 "Cmts.User" user "User.Comments")
		(21 "Eco1.User" user "User.Eco1")
		(23 "Eco2.User" user "User.Eco2")
		(25 "Edge.Cuts" user "Board Geometry/Outline")
		(27 "Margin" user)
		(31 "F.CrtYd" user "Package Geometry/Place Bound Top")
		(29 "B.CrtYd" user "Package Geometry/Place Bound Bottom")
		(35 "F.Fab" user "Ref Des/Assembly Top")
		(33 "B.Fab" user "Ref Des/Assembly Bottom")
	)
	(footprint ""
		(layer "F.Cu")
		(at 13.716 -97.028 180)
		(property "Reference" "C1C13"
			(at 0 0 180)
			(layer "F.SilkS")
			(hide yes)
			(effects
				(font
					(size 1.27 1.27)
				)
			)
		)
		(property "Value" ""
			(at 0 0 180)
			(layer "F.Fab")
			(effects
				(font
					(size 1.27 1.27)
				)
			)
		)
		(duplicate_pad_numbers_are_jumpers no)
		(fp_rect
			(start 0.3048 -0.1016)
			(end -0.3048 0.9906)
			(stroke
				(width 0)
				(type default)
			)
			(fill no)
			(layer "F.CrtYd")
		)
		(fp_line
			(start 0.3048 0.9906)
			(end 0.3048 -0.1016)
			(stroke
				(width 0.1)
				(type default)
			)
			(layer "F.Fab")
		)
		(fp_line
			(start 0.3048 -0.1016)
			(end -0.3048 -0.1016)
			(stroke
				(width 0.1)
				(type default)
			)
			(layer "F.Fab")
		)
		(fp_line
			(start -0.3048 0.9906)
			(end 0.3048 0.9906)
			(stroke
				(width 0.1)
				(type default)
			)
			(layer "F.Fab")
		)
		(fp_line
			(start -0.3048 -0.1016)
			(end -0.3048 0.9906)
			(stroke
				(width 0.1)
				(type default)
			)
			(layer "F.Fab")
		)
		(pad "1" smd rect
			(at 0 0 180)
			(size 0.508 0.508)
			(layers "F.Cu" "F.Mask" "F.Paste")
			(net "VR_PVCCIN_CPU1_VD12")
		)
		(pad "2" smd rect
			(at 0 0.889 180)
			(size 0.508 0.508)
			(layers "F.Cu" "F.Mask" "F.Paste")
			(net "GND")
		)
		(zone
			(layer "F.Cu")
			(hatch none 0.5)
			(connect_pads
				(clearance 0)
			)
			(min_thickness 0.25)
			(keepout
				(tracks allowed)
				(vias not_allowed)
				(pads allowed)
				(copperpour not_allowed)
				(footprints allowed)
			)
			(placement
				(enabled no)
				(sheetname "")
			)
			(fill
				(thermal_gap 0.5)
				(thermal_bridge_width 0.5)
				(island_removal_mode 0)
			)
			(polygon
				(pts
					(xy 13.462 -97.282) (xy 13.97 -97.282) (xy 13.97 -97.663) (xy 13.462 -97.663)
				)
			)
		)
		(zone
			(layer "F.Cu")
			(hatch none 0.5)
			(connect_pads
				(clearance 0)
			)
			(min_thickness 0.25)
			(keepout
				(tracks not_allowed)
				(vias allowed)
				(pads allowed)
				(copperpour not_allowed)
				(footprints allowed)
			)
			(placement
				(enabled no)
				(sheetname "")
			)
			(fill
				(thermal_gap 0.5)
				(thermal_bridge_width 0.5)
				(island_removal_mode 0)
			)
			(polygon
				(pts
					(xy 13.462 -97.282) (xy 13.97 -97.282) (xy 13.97 -97.663) (xy 13.462 -97.663)
				)
			)
		)
	)
	(footprint ""
		(layer "F.Cu")
		(at 87.158068 -140.208 -90)
		(property "Reference" "C2A11"
			(at 1.848866 0.752348 270)
			(unlocked yes)
			(layer "F.SilkS")
			(effects
				(font
					(size 1.27 0.9652)
					(thickness 0.1524)
				)
			)
		)
		(property "Value" ""
			(at 0 0 270)
			(layer "F.Fab")
			(effects
				(font
					(size 1.27 1.27)
				)
			)
		)
		(duplicate_pad_numbers_are_jumpers no)
		(fp_rect
			(start -0.500126 1.598422)
			(end 0.500126 -0.201422)
			(stroke
				(width 0)
				(type default)
			)
			(fill no)
			(layer "F.CrtYd")
		)
		(fp_line
			(start -0.500126 1.598422)
			(end -0.500126 -0.201422)
			(stroke
				(width 0.1)
				(type default)
			)
			(layer "F.Fab")
		)
		(fp_line
			(start 0.500126 1.598422)
			(end -0.500126 1.598422)
			(stroke
				(width 0.1)
				(type default)
			)
			(layer "F.Fab")
		)
		(fp_line
			(start -0.500126 -0.201422)
			(end 0.500126 -0.201422)
			(stroke
				(width 0.1)
				(type default)
			)
			(layer "F.Fab")
		)
		(fp_line
			(start 0.500126 -0.201422)
			(end 0.500126 1.598422)
			(stroke
				(width 0.1)
				(type default)
			)
			(layer "F.Fab")
		)
		(pad "1" smd rect
			(at 0 0 180)
			(size 0.889 0.9906)
			(layers "F.Cu" "F.Mask" "F.Paste")
			(net "PVDDQ_KLM")
		)
		(pad "2" smd rect
			(at 0 1.397 180)
			(size 0.889 0.9906)
			(layers "F.Cu" "F.Mask" "F.Paste")
			(net "GND")
		)
		(zone
			(layer "F.Cu")
			(hatch none 0.5)
			(connect_pads
				(clearance 0)
			)
			(min_thickness 0.25)
			(keepout
				(tracks allowed)
				(vias not_allowed)
				(pads allowed)
				(copperpour not_allowed)
				(footprints allowed)
			)
			(placement
				(enabled no)
				(sheetname "")
			)
			(fill
				(thermal_gap 0.5)
				(thermal_bridge_width 0.5)
				(island_removal_mode 0)
			)
			(polygon
				(pts
					(xy 86.205568 -140.7033) (xy 86.205568 -139.7127) (xy 86.713568 -139.7127) (xy 86.713568 -140.7033)
				)
			)
		)
		(zone
			(layer "F.Cu")
			(hatch none 0.5)
			(connect_pads
				(clearance 0)
			)
			(min_thickness 0.25)
			(keepout
				(tracks not_allowed)
				(vias allowed)
				(pads allowed)
				(copperpour not_allowed)
				(footprints allowed)
			)
			(placement
				(enabled no)
				(sheetname "")
			)
			(fill
				(thermal_gap 0.5)
				(thermal_bridge_width 0.5)
				(island_removal_mode 0)
			)
			(polygon
				(pts
					(xy 86.205568 -140.7033) (xy 86.205568 -139.7127) (xy 86.713568 -139.7127) (xy 86.713568 -140.7033)
				)
			)
		)
	)
	(footprint ""
		(layer "F.Cu")
		(at 182.5752 -55.3974 90)
		(property "Reference" "CT61"
			(at -4.6482 1.49987 90)
			(unlocked yes)
			(layer "F.SilkS")
			(effects
				(font
					(size 0.7874 0.5842)
					(thickness 0.1524)
				)
				(justify left)
			)
		)
		(property "Value" ""
			(at 0 0 90)
			(layer "F.Fab")
			(effects
				(font
					(size 1.27 1.27)
				)
			)
		)
		(duplicate_pad_numbers_are_jumpers no)
		(fp_poly
			(pts
				(xy 0.3048 -0.1016) (xy 0.3048 0.9906) (xy -0.3048 0.9906) (xy -0.3048 -0.1016)
			)
			(stroke
				(width 0)
				(type default)
			)
			(fill no)
			(layer "F.CrtYd")
		)
		(fp_line
			(start 0.3048 -0.1016)
			(end -0.3048 -0.1016)
			(stroke
				(width 0.1)
				(type default)
			)
			(layer "F.Fab")
		)
		(fp_line
			(start -0.3048 -0.1016)
			(end -0.3048 0.9906)
			(stroke
				(width 0.1)
				(type default)
			)
			(layer "F.Fab")
		)
		(fp_line
			(start 0.3048 0.9906)
			(end 0.3048 -0.1016)
			(stroke
				(width 0.1)
				(type default)
			)
			(layer "F.Fab")
		)
		(fp_line
			(start -0.3048 0.9906)
			(end 0.3048 0.9906)
			(stroke
				(width 0.1)
				(type default)
			)
			(layer "F.Fab")
		)
		(pad "1" smd rect
			(at 0 0 90)
			(size 0.508 0.508)
			(layers "F.Cu" "F.Mask" "F.Paste")
			(net "A_TSENSE_PVCCIO_CPU1")
		)
		(pad "2" smd rect
			(at 0 0.889 90)
			(size 0.508 0.508)
			(layers "F.Cu" "F.Mask" "F.Paste")
			(net "GND")
		)
		(zone
			(layer "F.Cu")
			(hatch none 0.5)
			(connect_pads
				(clearance 0)
			)
			(min_thickness 0.25)
			(keepout
				(tracks allowed)
				(vias not_allowed)
				(pads allowed)
				(copperpour not_allowed)
				(footprints allowed)
			)
			(placement
				(enabled no)
				(sheetname "")
			)
			(fill
				(thermal_gap 0.5)
				(thermal_bridge_width 0.5)
				(island_removal_mode 0)
			)
			(polygon
				(pts
					(xy 182.8292 -55.1434) (xy 182.8292 -55.6514) (xy 183.2102 -55.6514) (xy 183.2102 -55.1434)
				)
			)
		)
		(zone
			(layer "F.Cu")
			(hatch none 0.5)
			(connect_pads
				(clearance 0)
			)
			(min_thickness 0.25)
			(keepout
				(tracks not_allowed)
				(vias allowed)
				(pads allowed)
				(copperpour not_allowed)
				(footprints allowed)
			)
			(placement
				(enabled no)
				(sheetname "")
			)
			(fill
				(thermal_gap 0.5)
				(thermal_bridge_width 0.5)
				(island_removal_mode 0)
			)
			(polygon
				(pts
					(xy 183.2102 -55.1434) (xy 183.2102 -55.6514) (xy 182.8292 -55.6514) (xy 182.8292 -55.1434)
				)
			)
		)
	)
)
